FILE_TYPE = CONNECTIVITY;
{Allegro Design Entry HDL 17.2-2016 S081 (4005846) 1/11/2022}
"PAGE_NUMBER" = 107;
0"NC";
1"P3V3_AUX\g";
2"P3V3_AUX\g";
3"P12V_S3_AUX_CPU1_NVDIMM\g";
4"P12V_S3_AUX_CPU1_NVDIMM\g";
5"GND\g";
6"GND\g";
7"GND\g";
8"GND\g";
9"GND\g";
10"M_E_CPU1_SA_DQ<31:0>";
11"M_E_CPU1_SA_CB<7:0>";
12"M_E_CPU1_SB_CB<7:0>";
13"M_E_CPU1_SA_CA<6:0>";
14"M_E_CPU1_SB_CA<6:0>";
15"M_E_CPU1_SB_DQ<31:0>";
16"M_E_CPU1_SB_DQS_DP<9:0>";
17"M_E_CPU1_SA_DQS_DP<9:0>";
18"M_E_CPU1_SB_DQS_DN<9:0>";
19"M_E_CPU1_SA_DQS_DN<9:0>";
20"M_E_CPU1_ALERT_N";
21"I3C_SPD_DDREFGH_CPU1_LVC1_SCL_R2";
22"I3C_SPD_DDREFGH_CPU1_LVC1_SDA";
23"PD_CHE_CPU1_DIMM2_SAA";
24"RST_M_EF_CPU1_FPGA_N";
25"M_E_CPU1_SB_CB<0>";
26"M_E_CPU1_SB_CB<1>";
27"I3C_SPD_DDREFGH_CPU1_LVC1_SCL";
28"PWRGD_CHE_CPU1_DIMM2";
29"M_E_CPU1_SA_DQS_DN<9>";
30"M_E_CPU1_SA_DQS_DN<8>";
31"M_E_CPU1_SA_DQS_DN<7>";
32"M_E_CPU1_SA_DQS_DN<6>";
33"M_E_CPU1_SA_DQS_DN<5>";
34"M_E_CPU1_SA_DQS_DN<3>";
35"M_E_CPU1_SA_DQS_DN<4>";
36"M_E_CPU1_SA_DQS_DN<2>";
37"M_E_CPU1_SA_DQS_DN<1>";
38"M_E_CPU1_SA_DQS_DN<0>";
39"M_E_CPU1_SB_DQS_DN<9>";
40"M_E_CPU1_SB_DQS_DN<8>";
41"M_E_CPU1_SB_DQS_DN<7>";
42"M_E_CPU1_SB_DQS_DN<6>";
43"M_E_CPU1_SB_DQS_DN<5>";
44"M_E_CPU1_SB_DQS_DN<4>";
45"M_E_CPU1_SB_DQS_DN<2>";
46"M_E_CPU1_SB_DQS_DN<3>";
47"M_E_CPU1_SB_DQS_DN<1>";
48"M_E_CPU1_SB_DQS_DN<0>";
49"M_E_CPU1_SA_DQS_DP<9>";
50"M_E_CPU1_SA_DQS_DP<8>";
51"M_E_CPU1_SA_DQS_DP<7>";
52"M_E_CPU1_SA_DQS_DP<6>";
53"M_E_CPU1_SA_DQS_DP<5>";
54"M_E_CPU1_SA_DQS_DP<4>";
55"M_E_CPU1_SA_DQS_DP<3>";
56"M_E_CPU1_SA_DQS_DP<2>";
57"M_E_CPU1_SA_DQS_DP<1>";
58"M_E_CPU1_SA_DQS_DP<0>";
59"M_E_CPU1_SB_DQS_DP<9>";
60"M_E_CPU1_SB_DQS_DP<8>";
61"M_E_CPU1_SB_DQS_DP<7>";
62"M_E_CPU1_SB_DQS_DP<6>";
63"M_E_CPU1_SB_DQS_DP<5>";
64"M_E_CPU1_SB_DQS_DP<4>";
65"M_E_CPU1_SB_DQS_DP<3>";
66"M_E_CPU1_SB_DQS_DP<2>";
67"M_E_CPU1_SB_DQS_DP<1>";
68"M_E_CPU1_SB_DQS_DP<0>";
69"M_E_CPU1_SA_CB<2>";
70"TP_CHE_CPU1_DIMM2_FRU_1";
71"TP_CHE_CPU1_DIMM2_FRU_0";
72"M_E_CPU1_SA_DQ<10>";
73"M_E_CPU1_SB_DQ<31>";
74"M_E_CPU1_SA_DQ<7>";
75"TP_CHE_CPU1_DIMM2_FRU_2";
76"TP_CHE_CPU1_DIMM2_FRU_3";
77"TP_CHE_CPU1_DIMM2_FRU_4";
78"TP_CHE_CPU1_DIMM2_FRU_5";
79"TP_CHE_CPU1_DIMM2_FRU_6";
80"M_E_CPU1_SB_PAR";
81"M_E_CPU1_SA_PAR";
82"M_E_CPU1_SB_RSP<1>";
83"M_E_CPU1_SA_RSP<1>";
84"M_E_CPU1_SB_DQ<0>";
85"M_E_CPU1_SB_DQ<1>";
86"M_E_CPU1_SB_DQ<2>";
87"M_E_CPU1_SB_DQ<3>";
88"M_E_CPU1_SB_DQ<4>";
89"M_E_CPU1_SB_DQ<5>";
90"M_E_CPU1_SB_DQ<6>";
91"M_E_CPU1_SB_DQ<7>";
92"M_E_CPU1_SB_DQ<8>";
93"M_E_CPU1_SB_DQ<9>";
94"M_E_CPU1_SB_DQ<10>";
95"M_E_CPU1_SB_DQ<11>";
96"M_E_CPU1_SB_DQ<12>";
97"M_E_CPU1_SB_DQ<13>";
98"M_E_CPU1_SB_DQ<14>";
99"M_E_CPU1_SB_DQ<15>";
100"M_E_CPU1_SB_DQ<16>";
101"M_E_CPU1_SB_DQ<17>";
102"M_E_CPU1_SB_DQ<18>";
103"M_E_CPU1_SB_DQ<19>";
104"M_E_CPU1_SB_DQ<20>";
105"M_E_CPU1_SB_DQ<21>";
106"M_E_CPU1_SB_DQ<22>";
107"M_E_CPU1_SB_DQ<23>";
108"M_E_CPU1_SB_DQ<24>";
109"M_E_CPU1_SB_DQ<25>";
110"M_E_CPU1_SB_DQ<26>";
111"M_E_CPU1_SB_DQ<27>";
112"M_E_CPU1_SB_DQ<28>";
113"M_E_CPU1_SB_DQ<29>";
114"M_E_CPU1_SB_DQ<30>";
115"M_E_CPU1_SA_DQ<0>";
116"M_E_CPU1_SA_DQ<1>";
117"M_E_CPU1_SA_DQ<2>";
118"M_E_CPU1_SA_DQ<3>";
119"M_E_CPU1_SA_DQ<4>";
120"M_E_CPU1_SA_DQ<5>";
121"M_E_CPU1_SA_DQ<6>";
122"M_E_CPU1_SA_DQ<8>";
123"M_E_CPU1_SA_DQ<9>";
124"M_E_CPU1_SA_DQ<11>";
125"M_E_CPU1_SA_DQ<12>";
126"M_E_CPU1_SA_DQ<13>";
127"M_E_CPU1_SA_DQ<14>";
128"M_E_CPU1_SA_DQ<15>";
129"M_E_CPU1_SA_DQ<16>";
130"M_E_CPU1_SA_DQ<17>";
131"M_E_CPU1_SA_DQ<18>";
132"M_E_CPU1_SA_DQ<19>";
133"M_E_CPU1_SA_DQ<20>";
134"M_E_CPU1_SA_DQ<21>";
135"M_E_CPU1_SA_DQ<22>";
136"M_E_CPU1_SA_DQ<23>";
137"M_E_CPU1_SA_DQ<24>";
138"M_E_CPU1_SA_DQ<25>";
139"M_E_CPU1_SA_DQ<26>";
140"M_E_CPU1_SA_DQ<27>";
141"M_E_CPU1_SA_DQ<28>";
142"M_E_CPU1_SA_DQ<29>";
143"M_E_CPU1_SA_DQ<30>";
144"M_E_CPU1_SB_CS_N<3>";
145"M_E_CPU1_SA_CS_N<3>";
146"M_E_CPU1_SB_CS_N<2>";
147"M_E_CPU1_SA_CS_N<2>";
148"M_E_CPU1_CLK_DP<1>";
149"M_E_CPU1_CLK_DN<1>";
150"M_E_CPU1_SB_CB<2>";
151"M_E_CPU1_SB_CB<3>";
152"M_E_CPU1_SB_CB<4>";
153"M_E_CPU1_SB_CB<5>";
154"M_E_CPU1_SB_CB<6>";
155"M_E_CPU1_SA_CB<0>";
156"M_E_CPU1_SA_CB<3>";
157"M_E_CPU1_SA_CB<5>";
158"M_E_CPU1_SA_CB<6>";
159"M_E_CPU1_SB_CA<6>";
160"M_E_CPU1_SA_CA<6>";
161"M_E_CPU1_SB_CA<5>";
162"M_E_CPU1_SA_CA<5>";
163"M_E_CPU1_SB_CA<4>";
164"M_E_CPU1_SA_CA<4>";
165"M_E_CPU1_SB_CA<3>";
166"M_E_CPU1_SA_CA<3>";
167"M_E_CPU1_SB_CA<2>";
168"M_E_CPU1_SA_CA<2>";
169"M_E_CPU1_SB_CA<1>";
170"M_E_CPU1_SA_CA<1>";
171"M_E_CPU1_SB_CA<0>";
172"M_E_CPU1_SA_CA<0>";
173"M_E_CPU1_SB_CB<7>";
174"M_E_CPU1_SA_CB<1>";
175"M_E_CPU1_SA_CB<4>";
176"M_E_CPU1_SA_CB<7>";
177"M_E_CPU1_SA_DQ<31>";
178"PD_CHE_CPU1_DIMM2_SAA";
%"UNIVERSAL_GND"
"1","(-2275,0)","0","logical_power","I1";
;
HDL_POWER"GND"
CDS_LIB"logical_power";
"A"5;
%"TAP"
"1","(-850,3475)","0","standard","I100";
;
CDS_LIB"standard"
BODY_TYPE"PLUMBING"
HDL_TAP"TRUE";
"B \NAC \NWC"10;
"S \NAC"
BN"13"126;
%"TAP"
"1","(-850,3525)","0","standard","I101";
;
CDS_LIB"standard"
BODY_TYPE"PLUMBING"
HDL_TAP"TRUE";
"B \NAC \NWC"10;
"S \NAC"
BN"14"127;
%"TAP"
"1","(-850,3675)","0","standard","I102";
;
CDS_LIB"standard"
BODY_TYPE"PLUMBING"
HDL_TAP"TRUE";
"B \NAC \NWC"10;
"S \NAC"
BN"17"130;
%"TAP"
"1","(-850,3725)","0","standard","I103";
;
CDS_LIB"standard"
BODY_TYPE"PLUMBING"
HDL_TAP"TRUE";
"B \NAC \NWC"10;
"S \NAC"
BN"18"131;
%"TAP"
"1","(-850,3775)","0","standard","I104";
;
CDS_LIB"standard"
BODY_TYPE"PLUMBING"
HDL_TAP"TRUE";
"B \NAC \NWC"10;
"S \NAC"
BN"19"132;
%"TAP"
"1","(-850,3825)","0","standard","I105";
;
CDS_LIB"standard"
BODY_TYPE"PLUMBING"
HDL_TAP"TRUE";
"B \NAC \NWC"10;
"S \NAC"
BN"20"133;
%"TAP"
"1","(-850,3625)","0","standard","I106";
;
CDS_LIB"standard"
BODY_TYPE"PLUMBING"
HDL_TAP"TRUE";
"B \NAC \NWC"10;
"S \NAC"
BN"16"129;
%"TAP"
"1","(-850,3875)","0","standard","I107";
;
CDS_LIB"standard"
BODY_TYPE"PLUMBING"
HDL_TAP"TRUE";
"B \NAC \NWC"10;
"S \NAC"
BN"21"134;
%"TAP"
"1","(-850,3925)","0","standard","I108";
;
CDS_LIB"standard"
BODY_TYPE"PLUMBING"
HDL_TAP"TRUE";
"B \NAC \NWC"10;
"S \NAC"
BN"22"135;
%"TAP"
"1","(-850,3975)","0","standard","I109";
;
CDS_LIB"standard"
BODY_TYPE"PLUMBING"
HDL_TAP"TRUE";
"B \NAC \NWC"10;
"S \NAC"
BN"23"136;
%"TAP"
"1","(-850,4075)","0","standard","I110";
;
CDS_LIB"standard"
BODY_TYPE"PLUMBING"
HDL_TAP"TRUE";
"B \NAC \NWC"10;
"S \NAC"
BN"25"138;
%"TAP"
"1","(-850,4025)","0","standard","I111";
;
CDS_LIB"standard"
BODY_TYPE"PLUMBING"
HDL_TAP"TRUE";
"B \NAC \NWC"10;
"S \NAC"
BN"24"137;
%"TAP"
"1","(-850,4125)","0","standard","I112";
;
CDS_LIB"standard"
BODY_TYPE"PLUMBING"
HDL_TAP"TRUE";
"B \NAC \NWC"10;
"S \NAC"
BN"26"139;
%"TAP"
"1","(-850,4175)","0","standard","I113";
;
CDS_LIB"standard"
BODY_TYPE"PLUMBING"
HDL_TAP"TRUE";
"B \NAC \NWC"10;
"S \NAC"
BN"27"140;
%"TAP"
"1","(-850,4225)","0","standard","I114";
;
CDS_LIB"standard"
BODY_TYPE"PLUMBING"
HDL_TAP"TRUE";
"B \NAC \NWC"10;
"S \NAC"
BN"28"141;
%"TAP"
"1","(-850,4325)","0","standard","I115";
;
CDS_LIB"standard"
BODY_TYPE"PLUMBING"
HDL_TAP"TRUE";
"B \NAC \NWC"10;
"S \NAC"
BN"30"143;
%"TAP"
"1","(-850,4275)","0","standard","I116";
;
CDS_LIB"standard"
BODY_TYPE"PLUMBING"
HDL_TAP"TRUE";
"B \NAC \NWC"10;
"S \NAC"
BN"29"142;
%"TAP"
"1","(-2500,4375)","2","standard","I118";
;
CDS_LIB"standard"
BODY_TYPE"PLUMBING"
HDL_TAP"TRUE";
"B \NAC \NWC"13;
"S \NAC"
BN"6"160;
%"TAP"
"1","(-850,4375)","0","standard","I119";
;
CDS_LIB"standard"
BODY_TYPE"PLUMBING"
HDL_TAP"TRUE";
"B \NAC \NWC"10;
"S \NAC"
BN"31"177;
%"VCC_CORE"
"1","(-3325,2250)","0","logical_power","I12";
;
HDL_POWER"P3V3_AUX"
CDS_LIB"logical_power";
"A"1;
%"UNIVERSAL_GND"
"1","(875,125)","0","logical_power","I120";
;
HDL_POWER"GND"
CDS_LIB"logical_power";
"A"6;
%"UNIVERSAL_GND"
"1","(2500,125)","0","logical_power","I121";
;
HDL_POWER"GND"
CDS_LIB"logical_power";
"A"7;
%"Q_CAP"
"1","(875,500)","0","pure_quanta","I122";
;
PART_NUMBER"CH5221MEB00"
VOLTAGE"6.3V"
MATERIAL"X6S"
TOLERANCE"20%"
VALUE"2.2UF"
PACK_TYPE"C0402"
$LOCATION"C90"
CDS_LIB"pure_quanta"
$LOCATION"C90"
CDS_LOCATION"C90"
$SEC"1"
CDS_SEC"1";
"B"
$PN"2"6;
"A"
$PN"1"2;
%"VCC_CORE"
"1","(875,825)","0","logical_power","I123";
;
HDL_POWER"P3V3_AUX"
CDS_LIB"logical_power";
"A"2;
%"Q_CAP"
"1","(1875,500)","0","pure_quanta","I126";
;
PART_NUMBER"CH6103KEA00"
VOLTAGE"16V"
PACK_TYPE"C0805"
TOLERANCE"10%"
MATERIAL"X6S"
VALUE"10UF"
$LOCATION"C91"
CDS_LIB"pure_quanta"
$LOCATION"C91"
CDS_LOCATION"C91"
$SEC"1"
CDS_SEC"1";
"B"
$PN"2"7;
"A"
$PN"1"4;
%"VCC_CORE"
"1","(1875,825)","0","logical_power","I127";
;
HDL_POWER"P12V_S3_AUX_CPU1_NVDIMM"
CDS_LIB"logical_power";
"A"4;
%"Q_CAP"
"1","(2500,500)","0","pure_quanta","I128";
;
PART_NUMBER"CH6103KEA00"
PACK_TYPE"C0805"
VALUE"10UF"
TOLERANCE"10%"
VOLTAGE"16V"
MATERIAL"X6S"
$LOCATION"C92"
CDS_LIB"pure_quanta"
$LOCATION"C92"
CDS_LOCATION"C92"
$SEC"1"
CDS_SEC"1";
"B"
$PN"2"7;
"A"
$PN"1"4;
%"TAP"
"1","(1900,2425)","0","standard","I129";
;
CDS_LIB"standard"
BODY_TYPE"PLUMBING"
HDL_TAP"TRUE";
"B \NAC \NWC"16;
"S \NAC"
BN"0"68;
%"TAP"
"1","(1900,2525)","0","standard","I130";
;
CDS_LIB"standard"
BODY_TYPE"PLUMBING"
HDL_TAP"TRUE";
"B \NAC \NWC"16;
"S \NAC"
BN"1"67;
%"TAP"
"1","(1900,2725)","0","standard","I131";
;
CDS_LIB"standard"
BODY_TYPE"PLUMBING"
HDL_TAP"TRUE";
"B \NAC \NWC"16;
"S \NAC"
BN"3"65;
%"TAP"
"1","(1900,2625)","0","standard","I132";
;
CDS_LIB"standard"
BODY_TYPE"PLUMBING"
HDL_TAP"TRUE";
"B \NAC \NWC"16;
"S \NAC"
BN"2"66;
%"TAP"
"1","(1900,2825)","0","standard","I133";
;
CDS_LIB"standard"
BODY_TYPE"PLUMBING"
HDL_TAP"TRUE";
"B \NAC \NWC"16;
"S \NAC"
BN"4"64;
%"TAP"
"1","(1900,2925)","0","standard","I134";
;
CDS_LIB"standard"
BODY_TYPE"PLUMBING"
HDL_TAP"TRUE";
"B \NAC \NWC"16;
"S \NAC"
BN"5"63;
%"TAP"
"1","(1900,3025)","0","standard","I135";
;
CDS_LIB"standard"
BODY_TYPE"PLUMBING"
HDL_TAP"TRUE";
"B \NAC \NWC"16;
"S \NAC"
BN"6"62;
%"TAP"
"1","(1900,3125)","0","standard","I136";
;
CDS_LIB"standard"
BODY_TYPE"PLUMBING"
HDL_TAP"TRUE";
"B \NAC \NWC"16;
"S \NAC"
BN"7"61;
%"TAP"
"1","(1900,3225)","0","standard","I137";
;
CDS_LIB"standard"
BODY_TYPE"PLUMBING"
HDL_TAP"TRUE";
"B \NAC \NWC"16;
"S \NAC"
BN"8"60;
%"TAP"
"1","(2075,2375)","0","standard","I138";
;
CDS_LIB"standard"
BODY_TYPE"PLUMBING"
HDL_TAP"TRUE";
"B \NAC \NWC"18;
"S \NAC"
BN"0"48;
%"TAP"
"1","(2075,2475)","0","standard","I139";
;
CDS_LIB"standard"
BODY_TYPE"PLUMBING"
HDL_TAP"TRUE";
"B \NAC \NWC"18;
"S \NAC"
BN"1"47;
%"TAP"
"1","(2075,2675)","0","standard","I140";
;
CDS_LIB"standard"
BODY_TYPE"PLUMBING"
HDL_TAP"TRUE";
"B \NAC \NWC"18;
"S \NAC"
BN"3"46;
%"TAP"
"1","(2075,2575)","0","standard","I141";
;
CDS_LIB"standard"
BODY_TYPE"PLUMBING"
HDL_TAP"TRUE";
"B \NAC \NWC"18;
"S \NAC"
BN"2"45;
%"TAP"
"1","(2075,2775)","0","standard","I142";
;
CDS_LIB"standard"
BODY_TYPE"PLUMBING"
HDL_TAP"TRUE";
"B \NAC \NWC"18;
"S \NAC"
BN"4"44;
%"TAP"
"1","(2075,2875)","0","standard","I143";
;
CDS_LIB"standard"
BODY_TYPE"PLUMBING"
HDL_TAP"TRUE";
"B \NAC \NWC"18;
"S \NAC"
BN"5"43;
%"TAP"
"1","(2075,2975)","0","standard","I144";
;
CDS_LIB"standard"
BODY_TYPE"PLUMBING"
HDL_TAP"TRUE";
"B \NAC \NWC"18;
"S \NAC"
BN"6"42;
%"TAP"
"1","(2075,3175)","0","standard","I145";
;
CDS_LIB"standard"
BODY_TYPE"PLUMBING"
HDL_TAP"TRUE";
"B \NAC \NWC"18;
"S \NAC"
BN"8"40;
%"TAP"
"1","(2075,3075)","0","standard","I146";
;
CDS_LIB"standard"
BODY_TYPE"PLUMBING"
HDL_TAP"TRUE";
"B \NAC \NWC"18;
"S \NAC"
BN"7"41;
%"TAP"
"1","(2075,3275)","0","standard","I147";
;
CDS_LIB"standard"
BODY_TYPE"PLUMBING"
HDL_TAP"TRUE";
"B \NAC \NWC"18;
"S \NAC"
BN"9"39;
%"TAP"
"1","(1900,3475)","0","standard","I148";
;
CDS_LIB"standard"
BODY_TYPE"PLUMBING"
HDL_TAP"TRUE";
"B \NAC \NWC"17;
"S \NAC"
BN"0"58;
%"TAP"
"1","(1900,3325)","0","standard","I149";
;
CDS_LIB"standard"
BODY_TYPE"PLUMBING"
HDL_TAP"TRUE";
"B \NAC \NWC"16;
"S \NAC"
BN"9"59;
%"TAP"
"1","(1900,3575)","0","standard","I150";
;
CDS_LIB"standard"
BODY_TYPE"PLUMBING"
HDL_TAP"TRUE";
"B \NAC \NWC"17;
"S \NAC"
BN"1"57;
%"TAP"
"1","(1900,3775)","0","standard","I151";
;
CDS_LIB"standard"
BODY_TYPE"PLUMBING"
HDL_TAP"TRUE";
"B \NAC \NWC"17;
"S \NAC"
BN"3"55;
%"TAP"
"1","(1900,3675)","0","standard","I152";
;
CDS_LIB"standard"
BODY_TYPE"PLUMBING"
HDL_TAP"TRUE";
"B \NAC \NWC"17;
"S \NAC"
BN"2"56;
%"TAP"
"1","(1900,3875)","0","standard","I153";
;
CDS_LIB"standard"
BODY_TYPE"PLUMBING"
HDL_TAP"TRUE";
"B \NAC \NWC"17;
"S \NAC"
BN"4"54;
%"TAP"
"1","(1900,3975)","0","standard","I154";
;
CDS_LIB"standard"
BODY_TYPE"PLUMBING"
HDL_TAP"TRUE";
"B \NAC \NWC"17;
"S \NAC"
BN"5"53;
%"TAP"
"1","(1900,4075)","0","standard","I155";
;
CDS_LIB"standard"
BODY_TYPE"PLUMBING"
HDL_TAP"TRUE";
"B \NAC \NWC"17;
"S \NAC"
BN"6"52;
%"TAP"
"1","(1900,4275)","0","standard","I156";
;
CDS_LIB"standard"
BODY_TYPE"PLUMBING"
HDL_TAP"TRUE";
"B \NAC \NWC"17;
"S \NAC"
BN"8"50;
%"TAP"
"1","(1900,4175)","0","standard","I157";
;
CDS_LIB"standard"
BODY_TYPE"PLUMBING"
HDL_TAP"TRUE";
"B \NAC \NWC"17;
"S \NAC"
BN"7"51;
%"TAP"
"1","(2075,3425)","0","standard","I158";
;
CDS_LIB"standard"
BODY_TYPE"PLUMBING"
HDL_TAP"TRUE";
"B \NAC \NWC"19;
"S \NAC"
BN"0"38;
%"TAP"
"1","(2075,3525)","0","standard","I159";
;
CDS_LIB"standard"
BODY_TYPE"PLUMBING"
HDL_TAP"TRUE";
"B \NAC \NWC"19;
"S \NAC"
BN"1"37;
%"TAP"
"1","(2075,3625)","0","standard","I160";
;
CDS_LIB"standard"
BODY_TYPE"PLUMBING"
HDL_TAP"TRUE";
"B \NAC \NWC"19;
"S \NAC"
BN"2"36;
%"TAP"
"1","(2075,3825)","0","standard","I161";
;
CDS_LIB"standard"
BODY_TYPE"PLUMBING"
HDL_TAP"TRUE";
"B \NAC \NWC"19;
"S \NAC"
BN"4"35;
%"TAP"
"1","(2075,3725)","0","standard","I162";
;
CDS_LIB"standard"
BODY_TYPE"PLUMBING"
HDL_TAP"TRUE";
"B \NAC \NWC"19;
"S \NAC"
BN"3"34;
%"TAP"
"1","(2075,3925)","0","standard","I163";
;
CDS_LIB"standard"
BODY_TYPE"PLUMBING"
HDL_TAP"TRUE";
"B \NAC \NWC"19;
"S \NAC"
BN"5"33;
%"TAP"
"1","(2075,4025)","0","standard","I164";
;
CDS_LIB"standard"
BODY_TYPE"PLUMBING"
HDL_TAP"TRUE";
"B \NAC \NWC"19;
"S \NAC"
BN"6"32;
%"TAP"
"1","(2075,4125)","0","standard","I165";
;
CDS_LIB"standard"
BODY_TYPE"PLUMBING"
HDL_TAP"TRUE";
"B \NAC \NWC"19;
"S \NAC"
BN"7"31;
%"TAP"
"1","(2075,4225)","0","standard","I166";
;
CDS_LIB"standard"
BODY_TYPE"PLUMBING"
HDL_TAP"TRUE";
"B \NAC \NWC"19;
"S \NAC"
BN"8"30;
%"TAP"
"1","(2075,4325)","0","standard","I167";
;
CDS_LIB"standard"
BODY_TYPE"PLUMBING"
HDL_TAP"TRUE";
"B \NAC \NWC"19;
"S \NAC"
BN"9"29;
%"TAP"
"1","(1900,4375)","0","standard","I172";
;
CDS_LIB"standard"
BODY_TYPE"PLUMBING"
HDL_TAP"TRUE";
"B \NAC \NWC"17;
"S \NAC"
BN"9"49;
%"UNIVERSAL_GND"
"1","(3575,675)","0","logical_power","I174";
;
HDL_POWER"GND"
CDS_LIB"logical_power";
"A"8;
%"UNIVERSAL_GND"
"1","(5275,675)","0","logical_power","I176";
;
HDL_POWER"GND"
CDS_LIB"logical_power";
"A"9;
%"VCC_CORE"
"1","(3575,4925)","0","logical_power","I177";
;
HDL_POWER"P12V_S3_AUX_CPU1_NVDIMM"
CDS_LIB"logical_power";
"A"3;
%"SCONN288_ADR50017P087CC"
"3","(4425,2750)","0","pure_quanta","I179";
;
PART_NUMBER"DFHST8FS460"
MATERIAL"IO"
PART_TYPE"SMLF"
VALUE"SCONN288_ADR50017-P087CC"
$LOCATION"J26"
NEEDS_NO_SIZE"TRUE"
CDS_LMAN_SYM_OUTLINE"-450,1775,450,-1775"
CDS_LIB"pure_quanta"
CDS_LOCATION"J26"
$SEC"3"
CDS_SEC"3";
"G3"
$PN"G3"9;
"G2"
$PN"G2"9;
"G1"
$PN"G1"9;
"VSS62"
$PN"141"9;
"VSS61"
$PN"139"9;
"VSS60"
$PN"136"9;
"VSS58"
$PN"132"9;
"VSS104"
$PN"240"8;
"VSS102"
$PN"235"8;
"VSS100"
$PN"230"8;
"VIN_BULK2"
$PN"146"3;
"VIN_BULK1"
$PN"145"3;
"VIN_BULK0"
$PN"1"3;
"VSS126"
$PN"288"8;
"VSS125"
$PN"286"8;
"VSS124"
$PN"284"8;
"VSS123"
$PN"281"8;
"VSS122"
$PN"279"8;
"VSS121"
$PN"277"8;
"VSS120"
$PN"275"8;
"VSS119"
$PN"273"8;
"VSS118"
$PN"270"8;
"VSS117"
$PN"268"8;
"VSS116"
$PN"266"8;
"VSS115"
$PN"264"8;
"VSS114"
$PN"262"8;
"VSS113"
$PN"259"8;
"VSS112"
$PN"257"8;
"VSS111"
$PN"255"8;
"VSS110"
$PN"253"8;
"VSS109"
$PN"251"8;
"VSS108"
$PN"248"8;
"VSS107"
$PN"246"8;
"VSS106"
$PN"244"8;
"VSS105"
$PN"242"8;
"VSS103"
$PN"237"8;
"VSS101"
$PN"233"8;
"VSS99"
$PN"228"8;
"VSS98"
$PN"226"8;
"VSS97"
$PN"224"8;
"VSS96"
$PN"222"8;
"VSS95"
$PN"219"8;
"VSS94"
$PN"216"8;
"VSS93"
$PN"214"8;
"VSS92"
$PN"212"8;
"VSS91"
$PN"210"8;
"VSS90"
$PN"208"8;
"VSS89"
$PN"206"8;
"VSS88"
$PN"204"8;
"VSS87"
$PN"202"8;
"VSS86"
$PN"199"8;
"VSS85"
$PN"197"8;
"VSS84"
$PN"195"8;
"VSS83"
$PN"193"8;
"VSS82"
$PN"191"8;
"VSS81"
$PN"188"8;
"VSS80"
$PN"186"8;
"VSS79"
$PN"184"8;
"VSS78"
$PN"182"8;
"VSS77"
$PN"180"8;
"VSS76"
$PN"177"8;
"VSS75"
$PN"175"8;
"VSS74"
$PN"173"8;
"VSS73"
$PN"171"8;
"VSS72"
$PN"169"8;
"VSS71"
$PN"166"8;
"VSS70"
$PN"164"8;
"VSS69"
$PN"162"8;
"VSS68"
$PN"160"8;
"VSS67"
$PN"158"8;
"VSS66"
$PN"155"8;
"VSS65"
$PN"153"8;
"VSS64"
$PN"151"8;
"VSS63"
$PN"143"9;
"VSS59"
$PN"134"9;
"VSS57"
$PN"130"9;
"VSS56"
$PN"128"9;
"VSS55"
$PN"125"9;
"VSS54"
$PN"123"9;
"VSS53"
$PN"121"9;
"VSS52"
$PN"119"9;
"VSS51"
$PN"117"9;
"VSS50"
$PN"114"9;
"VSS49"
$PN"112"9;
"VSS48"
$PN"110"9;
"VSS47"
$PN"108"9;
"VSS46"
$PN"106"9;
"VSS45"
$PN"103"9;
"VSS44"
$PN"101"9;
"VSS43"
$PN"99"9;
"VSS42"
$PN"97"9;
"VSS41"
$PN"95"9;
"VSS40"
$PN"92"9;
"VSS39"
$PN"90"9;
"VSS38"
$PN"88"9;
"VSS37"
$PN"85"9;
"VSS36"
$PN"83"9;
"VSS35"
$PN"81"9;
"VSS34"
$PN"79"9;
"VSS33"
$PN"77"9;
"VSS32"
$PN"75"9;
"VSS31"
$PN"73"9;
"VSS30"
$PN"71"9;
"VSS29"
$PN"69"9;
"VSS28"
$PN"67"9;
"VSS27"
$PN"65"9;
"VSS26"
$PN"63"9;
"VSS25"
$PN"61"9;
"VSS24"
$PN"59"9;
"VSS23"
$PN"57"9;
"VSS22"
$PN"54"9;
"VSS21"
$PN"52"9;
"VSS20"
$PN"50"9;
"VSS19"
$PN"48"9;
"VSS18"
$PN"46"9;
"VSS17"
$PN"43"9;
"VSS16"
$PN"41"9;
"VSS15"
$PN"39"9;
"VSS14"
$PN"37"9;
"VSS13"
$PN"35"9;
"VSS12"
$PN"32"9;
"VSS11"
$PN"30"9;
"VSS10"
$PN"28"9;
"VSS9"
$PN"26"9;
"VSS8"
$PN"24"9;
"VSS7"
$PN"21"9;
"VSS6"
$PN"19"9;
"VSS5"
$PN"17"9;
"VSS4"
$PN"15"9;
"VSS3"
$PN"13"9;
"VSS2"
$PN"10"9;
"VSS1"
$PN"8"9;
"VSS0"
$PN"6"9;
%"SCONN288_ADR50017P087CC"
"1","(-1675,2650)","0","pure_quanta","I180";
;
PART_NUMBER"DFHST8FS460"
MATERIAL"IO"
VALUE"SCONN288_ADR50017-P087CC"
PART_TYPE"SMLF"
$LOCATION"J26"
NEEDS_NO_SIZE"TRUE"
CDS_LMAN_SYM_OUTLINE"-450,1875,450,-1875"
CDS_LIB"pure_quanta"
CDS_LOCATION"J26"
$SEC"1"
CDS_SEC"1";
"DQ31_A"
$PN"194"177;
"CB7_A"
$PN"205"176;
"CB4_A"
$PN"58"175;
"CB1_A"
$PN"53"174;
"CB7_B"
$PN"236"173;
"ALERT_N \B"
$PN"62"20;
"CA0_A"
$PN"66"172;
"CA0_B"
$PN"76"171;
"CA1_A"
$PN"211"170;
"CA1_B"
$PN"221"169;
"CA2_A"
$PN"68"168;
"CA2_B"
$PN"78"167;
"CA3_A"
$PN"213"166;
"CA3_B"
$PN"223"165;
"CA4_A"
$PN"70"164;
"CA4_B"
$PN"80"163;
"CA5_A"
$PN"215"162;
"CA5_B"
$PN"225"161;
"CA6_A"
$PN"72"160;
"CA6_B"
$PN"82"159;
"CB6_A"
$PN"203"158;
"CB5_A"
$PN"60"157;
"CB3_A"
$PN"198"156;
"CB2_A"
$PN"196"69;
"CB0_A"
$PN"51"155;
"CB6_B"
$PN"234"154;
"CB5_B"
$PN"91"153;
"CB4_B"
$PN"89"152;
"CB3_B"
$PN"243"151;
"CB2_B"
$PN"241"150;
"CB1_B"
$PN"98"26;
"CB0_B"
$PN"96"25;
"CK_C \B"
$PN"218"149;
"CK_T"
$PN"217"148;
"CS0_A_N"
$PN"64"147;
"CS0_B_N"
$PN"84"146;
"CS1_A_N"
$PN"209"145;
"CS1_B_N"
$PN"229"144;
"DQ30_A"
$PN"192"143;
"DQ29_A"
$PN"49"142;
"DQ28_A"
$PN"47"141;
"DQ27_A"
$PN"187"140;
"DQ26_A"
$PN"185"139;
"DQ25_A"
$PN"42"138;
"DQ24_A"
$PN"40"137;
"DQ23_A"
$PN"183"136;
"DQ22_A"
$PN"181"135;
"DQ21_A"
$PN"38"134;
"DQ20_A"
$PN"36"133;
"DQ19_A"
$PN"176"132;
"DQ18_A"
$PN"174"131;
"DQ17_A"
$PN"31"130;
"DQ16_A"
$PN"29"129;
"DQ15_A"
$PN"172"128;
"DQ14_A"
$PN"170"127;
"DQ13_A"
$PN"27"126;
"DQ12_A"
$PN"25"125;
"DQ11_A"
$PN"165"124;
"DQ10_A"
$PN"163"72;
"DQ9_A"
$PN"20"123;
"DQ8_A"
$PN"18"122;
"DQ7_A"
$PN"161"74;
"DQ6_A"
$PN"159"121;
"DQ5_A"
$PN"16"120;
"DQ4_A"
$PN"14"119;
"DQ3_A"
$PN"154"118;
"DQ2_A"
$PN"152"117;
"DQ1_A"
$PN"9"116;
"DQ0_A"
$PN"7"115;
"DQ31_B"
$PN"287"73;
"DQ30_B"
$PN"285"114;
"DQ29_B"
$PN"142"113;
"DQ28_B"
$PN"140"112;
"DQ27_B"
$PN"280"111;
"DQ26_B"
$PN"278"110;
"DQ25_B"
$PN"135"109;
"DQ24_B"
$PN"133"108;
"DQ23_B"
$PN"276"107;
"DQ22_B"
$PN"274"106;
"DQ21_B"
$PN"131"105;
"DQ20_B"
$PN"129"104;
"DQ19_B"
$PN"269"103;
"DQ18_B"
$PN"267"102;
"DQ17_B"
$PN"124"101;
"DQ16_B"
$PN"122"100;
"DQ15_B"
$PN"265"99;
"DQ14_B"
$PN"263"98;
"DQ13_B"
$PN"120"97;
"DQ12_B"
$PN"118"96;
"DQ11_B"
$PN"258"95;
"DQ10_B"
$PN"256"94;
"DQ9_B"
$PN"113"93;
"DQ8_B"
$PN"111"92;
"DQ7_B"
$PN"254"91;
"DQ6_B"
$PN"252"90;
"DQ5_B"
$PN"109"89;
"DQ4_B"
$PN"107"88;
"DQ3_B"
$PN"247"87;
"DQ2_B"
$PN"245"86;
"DQ1_B"
$PN"102"85;
"DQ0_B"
$PN"100"84;
"HSA"
$PN"148"23;
"HSCL"
$PN"4"21;
"HSDA"
$PN"5"22;
"LBD||RSP_A_N"
$PN"86"83;
"LBS||RSP_B_N"
$PN"87"82;
"PAR_A"
$PN"74"81;
"PAR_B"
$PN"227"80;
"PWR_GOOD||FAIL_N"
$PN"147"28;
"RESET_N \B"
$PN"207"24;
"RFU6"
$PN"232"79;
"RFU5"
$PN"231"78;
"RFU4"
$PN"220"77;
"RFU3"
$PN"150"76;
"RFU2"
$PN"149"75;
"RFU1"
$PN"144"70;
"RFU0"
$PN"2"71;
"VIN_MGMT"
$PN"3"1;
%"SCONN288_ADR50017P087CC"
"2","(1000,3375)","0","pure_quanta","I181";
;
PART_NUMBER"DFHST8FS460"
PART_TYPE"SMLF"
MATERIAL"IO"
VALUE"SCONN288_ADR50017-P087CC"
LOCATION"J26"
NEEDS_NO_SIZE"TRUE"
CDS_LMAN_SYM_OUTLINE"-600,1150,600,-1150"
CDS_LIB"pure_quanta"
$SEC"2"
CDS_SEC"2";
"DQS7_A_C||TDQS7_A_C \B"
$PN"178"31;
"DQS6_A_T||TDQS6_A_T"
$PN"168"52;
"DQS8_B_T||TDQS8_B_T"
$PN"283"60;
"DQS8_B_C||TDQS8_B_C \B"
$PN"282"40;
"DQS7_B_T||TDQS7_B_T"
$PN"272"61;
"DQS0_A_C \B"
$PN"12"38;
"DQS0_A_T"
$PN"11"58;
"DQS0_B_C \B"
$PN"105"48;
"DQS0_B_T"
$PN"104"68;
"DQS1_A_C \B"
$PN"23"37;
"DQS1_A_T"
$PN"22"57;
"DQS1_B_C \B"
$PN"116"47;
"DQS1_B_T"
$PN"115"67;
"DQS2_A_C \B"
$PN"34"36;
"DQS2_A_T"
$PN"33"56;
"DQS2_B_C \B"
$PN"127"45;
"DQS2_B_T"
$PN"126"66;
"DQS3_A_C \B"
$PN"45"34;
"DQS3_A_T"
$PN"44"55;
"DQS3_B_C \B"
$PN"138"46;
"DQS3_B_T"
$PN"137"65;
"DQS4_A_C \B"
$PN"56"35;
"DQS4_A_T"
$PN"55"54;
"DQS4_B_C \B"
$PN"238"44;
"DQS4_B_T"
$PN"239"64;
"DQS5_A_C||TDQS5_A_C||DQS5_A_T||TDQS5_A_T \B"
$PN"156"33;
"DQS5_A_T||TDQS5_A_T"
$PN"157"53;
"DQS5_B_C||TDQS5_B_C \B"
$PN"249"43;
"DQS5_B_T||TDQS5_B_T"
$PN"250"63;
"DQS6_A_C||TDQS6_A_C||DQS6_A_T||TDQS6_A_T \B"
$PN"167"32;
"DQS6_B_C||TDQS6_B_C \B"
$PN"260"42;
"DQS6_B_T||TDQS6_B_T"
$PN"261"62;
"DQS7_A_T||TDQS7_A_T"
$PN"179"51;
"DQS7_B_C||TDQS7_B_C \B"
$PN"271"41;
"DQS8_A_C||TDQS8_A_C \B"
$PN"189"30;
"DQS8_A_T||TDQS8_A_T"
$PN"190"50;
"DQS9_A_C||TDQS9_A_C \B"
$PN"200"29;
"DQS9_A_T||TDQS9_A_T"
$PN"201"49;
"DQS9_B_C||TDQS9_B_C \B"
$PN"94"39;
"DQS9_B_T||TDQS9_B_T||DBI4_B_N"
$PN"93"59;
%"Q_RES"
"1","(-3500,1675)","0","pure_quanta","I183";
;
PART_NUMBER"CS04992FB07"
VALUE"49.9"
MATERIAL"CHIP"
$LOCATION"R3900"
CDS_LIB"pure_quanta"
PACK_TYPE"0402LF"
TOLERANCE"1%"
WATTAGE"1/16W"
CDS_LOCATION"R3900"
$SEC"1"
CDS_SEC"1";
"B"
$PN"2"27;
"A"
$PN"1"21;
%"Q_RES"
"2","(-2275,225)","0","pure_quanta","I2";
;
PART_NUMBER"CS31542FB02"
PACK_TYPE"0402LF"
WATTAGE"1/16W"
MATERIAL"CHIP"
TOLERANCE"1%"
VALUE"15.4K"
$LOCATION"R78"
CDS_LIB"pure_quanta"
CDS_LOCATION"R78"
$SEC"1"
CDS_SEC"1";
"A"
$PN"1"178;
"B"
$PN"2"5;
%"TAP"
"1","(-2500,2175)","2","standard","I25";
;
CDS_LIB"standard"
BODY_TYPE"PLUMBING"
HDL_TAP"TRUE";
"B \NAC \NWC"12;
"S \NAC"
BN"0"25;
%"TAP"
"1","(-2500,2225)","2","standard","I26";
;
CDS_LIB"standard"
BODY_TYPE"PLUMBING"
HDL_TAP"TRUE";
"B \NAC \NWC"12;
"S \NAC"
BN"1"26;
%"TAP"
"1","(-2500,2275)","2","standard","I27";
;
CDS_LIB"standard"
BODY_TYPE"PLUMBING"
HDL_TAP"TRUE";
"B \NAC \NWC"12;
"S \NAC"
BN"2"150;
%"TAP"
"1","(-850,1175)","0","standard","I28";
;
CDS_LIB"standard"
BODY_TYPE"PLUMBING"
HDL_TAP"TRUE";
"B \NAC \NWC"15;
"S \NAC"
BN"0"84;
%"TAP"
"1","(-850,1225)","0","standard","I29";
;
CDS_LIB"standard"
BODY_TYPE"PLUMBING"
HDL_TAP"TRUE";
"B \NAC \NWC"15;
"S \NAC"
BN"1"85;
%"TAP"
"1","(-850,1375)","0","standard","I30";
;
CDS_LIB"standard"
BODY_TYPE"PLUMBING"
HDL_TAP"TRUE";
"B \NAC \NWC"15;
"S \NAC"
BN"4"88;
%"TAP"
"1","(-850,1275)","0","standard","I31";
;
CDS_LIB"standard"
BODY_TYPE"PLUMBING"
HDL_TAP"TRUE";
"B \NAC \NWC"15;
"S \NAC"
BN"2"86;
%"TAP"
"1","(-850,1325)","0","standard","I32";
;
CDS_LIB"standard"
BODY_TYPE"PLUMBING"
HDL_TAP"TRUE";
"B \NAC \NWC"15;
"S \NAC"
BN"3"87;
%"TAP"
"1","(-850,1525)","0","standard","I33";
;
CDS_LIB"standard"
BODY_TYPE"PLUMBING"
HDL_TAP"TRUE";
"B \NAC \NWC"15;
"S \NAC"
BN"7"91;
%"TAP"
"1","(-850,1475)","0","standard","I34";
;
CDS_LIB"standard"
BODY_TYPE"PLUMBING"
HDL_TAP"TRUE";
"B \NAC \NWC"15;
"S \NAC"
BN"6"90;
%"TAP"
"1","(-850,1425)","0","standard","I35";
;
CDS_LIB"standard"
BODY_TYPE"PLUMBING"
HDL_TAP"TRUE";
"B \NAC \NWC"15;
"S \NAC"
BN"5"89;
%"TAP"
"1","(-850,1775)","0","standard","I36";
;
CDS_LIB"standard"
BODY_TYPE"PLUMBING"
HDL_TAP"TRUE";
"B \NAC \NWC"15;
"S \NAC"
BN"12"96;
%"TAP"
"1","(-850,1725)","0","standard","I37";
;
CDS_LIB"standard"
BODY_TYPE"PLUMBING"
HDL_TAP"TRUE";
"B \NAC \NWC"15;
"S \NAC"
BN"11"95;
%"TAP"
"1","(-850,1675)","0","standard","I38";
;
CDS_LIB"standard"
BODY_TYPE"PLUMBING"
HDL_TAP"TRUE";
"B \NAC \NWC"15;
"S \NAC"
BN"10"94;
%"TAP"
"1","(-850,1625)","0","standard","I39";
;
CDS_LIB"standard"
BODY_TYPE"PLUMBING"
HDL_TAP"TRUE";
"B \NAC \NWC"15;
"S \NAC"
BN"9"93;
%"TAP"
"1","(-850,1575)","0","standard","I40";
;
CDS_LIB"standard"
BODY_TYPE"PLUMBING"
HDL_TAP"TRUE";
"B \NAC \NWC"15;
"S \NAC"
BN"8"92;
%"TAP"
"1","(-850,1825)","0","standard","I41";
;
CDS_LIB"standard"
BODY_TYPE"PLUMBING"
HDL_TAP"TRUE";
"B \NAC \NWC"15;
"S \NAC"
BN"13"97;
%"TAP"
"1","(-850,1875)","0","standard","I42";
;
CDS_LIB"standard"
BODY_TYPE"PLUMBING"
HDL_TAP"TRUE";
"B \NAC \NWC"15;
"S \NAC"
BN"14"98;
%"TAP"
"1","(-850,1925)","0","standard","I43";
;
CDS_LIB"standard"
BODY_TYPE"PLUMBING"
HDL_TAP"TRUE";
"B \NAC \NWC"15;
"S \NAC"
BN"15"99;
%"TAP"
"1","(-850,1975)","0","standard","I44";
;
CDS_LIB"standard"
BODY_TYPE"PLUMBING"
HDL_TAP"TRUE";
"B \NAC \NWC"15;
"S \NAC"
BN"16"100;
%"TAP"
"1","(-850,2025)","0","standard","I45";
;
CDS_LIB"standard"
BODY_TYPE"PLUMBING"
HDL_TAP"TRUE";
"B \NAC \NWC"15;
"S \NAC"
BN"17"101;
%"TAP"
"1","(-850,2275)","0","standard","I46";
;
CDS_LIB"standard"
BODY_TYPE"PLUMBING"
HDL_TAP"TRUE";
"B \NAC \NWC"15;
"S \NAC"
BN"22"106;
%"TAP"
"1","(-850,2225)","0","standard","I47";
;
CDS_LIB"standard"
BODY_TYPE"PLUMBING"
HDL_TAP"TRUE";
"B \NAC \NWC"15;
"S \NAC"
BN"21"105;
%"TAP"
"1","(-850,2175)","0","standard","I48";
;
CDS_LIB"standard"
BODY_TYPE"PLUMBING"
HDL_TAP"TRUE";
"B \NAC \NWC"15;
"S \NAC"
BN"20"104;
%"TAP"
"1","(-850,2125)","0","standard","I49";
;
CDS_LIB"standard"
BODY_TYPE"PLUMBING"
HDL_TAP"TRUE";
"B \NAC \NWC"15;
"S \NAC"
BN"19"103;
%"TAP"
"1","(-850,2075)","0","standard","I50";
;
CDS_LIB"standard"
BODY_TYPE"PLUMBING"
HDL_TAP"TRUE";
"B \NAC \NWC"15;
"S \NAC"
BN"18"102;
%"TAP"
"1","(-2500,2325)","2","standard","I51";
;
CDS_LIB"standard"
BODY_TYPE"PLUMBING"
HDL_TAP"TRUE";
"B \NAC \NWC"12;
"S \NAC"
BN"3"151;
%"TAP"
"1","(-2500,2375)","2","standard","I52";
;
CDS_LIB"standard"
BODY_TYPE"PLUMBING"
HDL_TAP"TRUE";
"B \NAC \NWC"12;
"S \NAC"
BN"4"152;
%"TAP"
"1","(-2500,2425)","2","standard","I53";
;
CDS_LIB"standard"
BODY_TYPE"PLUMBING"
HDL_TAP"TRUE";
"B \NAC \NWC"12;
"S \NAC"
BN"5"153;
%"TAP"
"1","(-2500,2525)","2","standard","I54";
;
CDS_LIB"standard"
BODY_TYPE"PLUMBING"
HDL_TAP"TRUE";
"B \NAC \NWC"12;
"S \NAC"
BN"7"173;
%"TAP"
"1","(-2500,2475)","2","standard","I55";
;
CDS_LIB"standard"
BODY_TYPE"PLUMBING"
HDL_TAP"TRUE";
"B \NAC \NWC"12;
"S \NAC"
BN"6"154;
%"TAP"
"1","(-2500,2625)","2","standard","I56";
;
CDS_LIB"standard"
BODY_TYPE"PLUMBING"
HDL_TAP"TRUE";
"B \NAC \NWC"11;
"S \NAC"
BN"0"155;
%"TAP"
"1","(-2500,2775)","2","standard","I57";
;
CDS_LIB"standard"
BODY_TYPE"PLUMBING"
HDL_TAP"TRUE";
"B \NAC \NWC"11;
"S \NAC"
BN"3"156;
%"TAP"
"1","(-2500,2725)","2","standard","I58";
;
CDS_LIB"standard"
BODY_TYPE"PLUMBING"
HDL_TAP"TRUE";
"B \NAC \NWC"11;
"S \NAC"
BN"2"69;
%"TAP"
"1","(-2500,2675)","2","standard","I59";
;
CDS_LIB"standard"
BODY_TYPE"PLUMBING"
HDL_TAP"TRUE";
"B \NAC \NWC"11;
"S \NAC"
BN"1"174;
%"TAP"
"1","(-2500,2875)","2","standard","I60";
;
CDS_LIB"standard"
BODY_TYPE"PLUMBING"
HDL_TAP"TRUE";
"B \NAC \NWC"11;
"S \NAC"
BN"5"157;
%"TAP"
"1","(-2500,2975)","2","standard","I61";
;
CDS_LIB"standard"
BODY_TYPE"PLUMBING"
HDL_TAP"TRUE";
"B \NAC \NWC"11;
"S \NAC"
BN"7"176;
%"TAP"
"1","(-2500,2925)","2","standard","I62";
;
CDS_LIB"standard"
BODY_TYPE"PLUMBING"
HDL_TAP"TRUE";
"B \NAC \NWC"11;
"S \NAC"
BN"6"158;
%"TAP"
"1","(-2500,2825)","2","standard","I63";
;
CDS_LIB"standard"
BODY_TYPE"PLUMBING"
HDL_TAP"TRUE";
"B \NAC \NWC"11;
"S \NAC"
BN"4"175;
%"TAP"
"1","(-2500,3775)","2","standard","I64";
;
CDS_LIB"standard"
BODY_TYPE"PLUMBING"
HDL_TAP"TRUE";
"B \NAC \NWC"14;
"S \NAC"
BN"2"167;
%"TAP"
"1","(-2500,3725)","2","standard","I65";
;
CDS_LIB"standard"
BODY_TYPE"PLUMBING"
HDL_TAP"TRUE";
"B \NAC \NWC"14;
"S \NAC"
BN"1"169;
%"TAP"
"1","(-2500,3675)","2","standard","I66";
;
CDS_LIB"standard"
BODY_TYPE"PLUMBING"
HDL_TAP"TRUE";
"B \NAC \NWC"14;
"S \NAC"
BN"0"171;
%"TAP"
"1","(-2500,3825)","2","standard","I67";
;
CDS_LIB"standard"
BODY_TYPE"PLUMBING"
HDL_TAP"TRUE";
"B \NAC \NWC"14;
"S \NAC"
BN"3"165;
%"TAP"
"1","(-2500,3975)","2","standard","I68";
;
CDS_LIB"standard"
BODY_TYPE"PLUMBING"
HDL_TAP"TRUE";
"B \NAC \NWC"14;
"S \NAC"
BN"6"159;
%"TAP"
"1","(-2500,3925)","2","standard","I69";
;
CDS_LIB"standard"
BODY_TYPE"PLUMBING"
HDL_TAP"TRUE";
"B \NAC \NWC"14;
"S \NAC"
BN"5"161;
%"TAP"
"1","(-2500,3875)","2","standard","I70";
;
CDS_LIB"standard"
BODY_TYPE"PLUMBING"
HDL_TAP"TRUE";
"B \NAC \NWC"14;
"S \NAC"
BN"4"163;
%"TAP"
"1","(-2500,4075)","2","standard","I71";
;
CDS_LIB"standard"
BODY_TYPE"PLUMBING"
HDL_TAP"TRUE";
"B \NAC \NWC"13;
"S \NAC"
BN"0"172;
%"TAP"
"1","(-2500,4125)","2","standard","I72";
;
CDS_LIB"standard"
BODY_TYPE"PLUMBING"
HDL_TAP"TRUE";
"B \NAC \NWC"13;
"S \NAC"
BN"1"170;
%"TAP"
"1","(-2500,4175)","2","standard","I73";
;
CDS_LIB"standard"
BODY_TYPE"PLUMBING"
HDL_TAP"TRUE";
"B \NAC \NWC"13;
"S \NAC"
BN"2"168;
%"TAP"
"1","(-2500,4275)","2","standard","I74";
;
CDS_LIB"standard"
BODY_TYPE"PLUMBING"
HDL_TAP"TRUE";
"B \NAC \NWC"13;
"S \NAC"
BN"4"164;
%"TAP"
"1","(-2500,4225)","2","standard","I75";
;
CDS_LIB"standard"
BODY_TYPE"PLUMBING"
HDL_TAP"TRUE";
"B \NAC \NWC"13;
"S \NAC"
BN"3"166;
%"TAP"
"1","(-2500,4325)","2","standard","I76";
;
CDS_LIB"standard"
BODY_TYPE"PLUMBING"
HDL_TAP"TRUE";
"B \NAC \NWC"13;
"S \NAC"
BN"5"162;
%"TAP"
"1","(-850,2325)","0","standard","I77";
;
CDS_LIB"standard"
BODY_TYPE"PLUMBING"
HDL_TAP"TRUE";
"B \NAC \NWC"15;
"S \NAC"
BN"23"107;
%"TAP"
"1","(-850,2525)","0","standard","I78";
;
CDS_LIB"standard"
BODY_TYPE"PLUMBING"
HDL_TAP"TRUE";
"B \NAC \NWC"15;
"S \NAC"
BN"27"111;
%"TAP"
"1","(-850,2425)","0","standard","I79";
;
CDS_LIB"standard"
BODY_TYPE"PLUMBING"
HDL_TAP"TRUE";
"B \NAC \NWC"15;
"S \NAC"
BN"25"109;
%"TAP"
"1","(-850,2475)","0","standard","I80";
;
CDS_LIB"standard"
BODY_TYPE"PLUMBING"
HDL_TAP"TRUE";
"B \NAC \NWC"15;
"S \NAC"
BN"26"110;
%"TAP"
"1","(-850,2375)","0","standard","I81";
;
CDS_LIB"standard"
BODY_TYPE"PLUMBING"
HDL_TAP"TRUE";
"B \NAC \NWC"15;
"S \NAC"
BN"24"108;
%"TAP"
"1","(-850,2725)","0","standard","I82";
;
CDS_LIB"standard"
BODY_TYPE"PLUMBING"
HDL_TAP"TRUE";
"B \NAC \NWC"15;
"S \NAC"
BN"31"73;
%"TAP"
"1","(-850,2675)","0","standard","I83";
;
CDS_LIB"standard"
BODY_TYPE"PLUMBING"
HDL_TAP"TRUE";
"B \NAC \NWC"15;
"S \NAC"
BN"30"114;
%"TAP"
"1","(-850,2625)","0","standard","I84";
;
CDS_LIB"standard"
BODY_TYPE"PLUMBING"
HDL_TAP"TRUE";
"B \NAC \NWC"15;
"S \NAC"
BN"29"113;
%"TAP"
"1","(-850,2575)","0","standard","I85";
;
CDS_LIB"standard"
BODY_TYPE"PLUMBING"
HDL_TAP"TRUE";
"B \NAC \NWC"15;
"S \NAC"
BN"28"112;
%"TAP"
"1","(-850,2825)","0","standard","I86";
;
CDS_LIB"standard"
BODY_TYPE"PLUMBING"
HDL_TAP"TRUE";
"B \NAC \NWC"10;
"S \NAC"
BN"0"115;
%"TAP"
"1","(-850,2925)","0","standard","I87";
;
CDS_LIB"standard"
BODY_TYPE"PLUMBING"
HDL_TAP"TRUE";
"B \NAC \NWC"10;
"S \NAC"
BN"2"117;
%"TAP"
"1","(-850,2875)","0","standard","I88";
;
CDS_LIB"standard"
BODY_TYPE"PLUMBING"
HDL_TAP"TRUE";
"B \NAC \NWC"10;
"S \NAC"
BN"1"116;
%"TAP"
"1","(-850,3025)","0","standard","I89";
;
CDS_LIB"standard"
BODY_TYPE"PLUMBING"
HDL_TAP"TRUE";
"B \NAC \NWC"10;
"S \NAC"
BN"4"119;
%"TAP"
"1","(-850,2975)","0","standard","I90";
;
CDS_LIB"standard"
BODY_TYPE"PLUMBING"
HDL_TAP"TRUE";
"B \NAC \NWC"10;
"S \NAC"
BN"3"118;
%"TAP"
"1","(-850,3275)","0","standard","I91";
;
CDS_LIB"standard"
BODY_TYPE"PLUMBING"
HDL_TAP"TRUE";
"B \NAC \NWC"10;
"S \NAC"
BN"9"123;
%"TAP"
"1","(-850,3125)","0","standard","I92";
;
CDS_LIB"standard"
BODY_TYPE"PLUMBING"
HDL_TAP"TRUE";
"B \NAC \NWC"10;
"S \NAC"
BN"6"121;
%"TAP"
"1","(-850,3225)","0","standard","I93";
;
CDS_LIB"standard"
BODY_TYPE"PLUMBING"
HDL_TAP"TRUE";
"B \NAC \NWC"10;
"S \NAC"
BN"8"122;
%"TAP"
"1","(-850,3175)","0","standard","I94";
;
CDS_LIB"standard"
BODY_TYPE"PLUMBING"
HDL_TAP"TRUE";
"B \NAC \NWC"10;
"S \NAC"
BN"7"74;
%"TAP"
"1","(-850,3075)","0","standard","I95";
;
CDS_LIB"standard"
BODY_TYPE"PLUMBING"
HDL_TAP"TRUE";
"B \NAC \NWC"10;
"S \NAC"
BN"5"120;
%"TAP"
"1","(-850,3325)","0","standard","I96";
;
CDS_LIB"standard"
BODY_TYPE"PLUMBING"
HDL_TAP"TRUE";
"B \NAC \NWC"10;
"S \NAC"
BN"10"72;
%"TAP"
"1","(-850,3375)","0","standard","I97";
;
CDS_LIB"standard"
BODY_TYPE"PLUMBING"
HDL_TAP"TRUE";
"B \NAC \NWC"10;
"S \NAC"
BN"11"124;
%"TAP"
"1","(-850,3425)","0","standard","I98";
;
CDS_LIB"standard"
BODY_TYPE"PLUMBING"
HDL_TAP"TRUE";
"B \NAC \NWC"10;
"S \NAC"
BN"12"125;
%"TAP"
"1","(-850,3575)","0","standard","I99";
;
CDS_LIB"standard"
BODY_TYPE"PLUMBING"
HDL_TAP"TRUE";
"B \NAC \NWC"10;
"S \NAC"
BN"15"128;
END.
